FILE_TYPE = MACRO_DRAWING;
SET COLOR_WIRE YELLOW;
SET COLOR_PROP ORANGE;
SET COLOR_DOT WHITE;
SET COLOR_ARC YELLOW;
SET COLOR_BODY GREEN;
SET COLOR_NOTE PURPLE;
SET PROP_DISPLAY VALUE;
SET PAGE_NUMBER P203;
FORCEADD QUANTA_TITLE_BLOCK_C..1
(0 0);
FORCEPROP 1 LAST CUSTOM_TXT_CDS <NAME_2>
J 0
(-3175 50);
FORCEPROP 1 LAST CUSTOM_TXT_CDS <NAME_1>
J 0
(-3175 175);
FORCEPROP 1 LAST CUSTOM_TXT_CDS <Q_NUMBER>
J 0
(-1403 103);
DISPLAY 1.212766 (-1403 103);
FORCEPROP 1 LAST CUSTOM_TXT_CDS <Q_PROJ>
J 0
(-2382 102);
DISPLAY 1.212766 (-2382 102);
FORCEPROP 1 LAST CUSTOM_TXT_CDS <Q_REV>
J 0
(-184 103);
DISPLAY 1.212766 (-184 103);
FORCEPROP 1 LAST CUSTOM_TXT_CDS <CON_LAST_MODIFIED>
J 0
(-1885 15);
DISPLAY 0.978723 (-1885 15);
FORCEPROP 1 LAST CUSTOM_TXT_CDS <CON_PAGE_NUM> OF <CON_TOTAL_PAGES>
J 0
(-446 18);
DISPLAY 0.978723 (-446 18);
FORCEPROP 1 LAST Q_TITLE Blank
J 0
(-9366 26);
DISPLAY 2.446809 (-9366 26);
PAINT GREEN (-9366 26);
FORCEPROP 2 LAST PAGE_BORDER TRUE
J 0
(-7890 5250);
DISPLAY 0.638298 (-7890 5250);
PAINT PINK (-7890 5250);
DISPLAY INVISIBLE (-7890 5250);
FORCEPROP 1 LAST CDS_LMAN_SYM_OUTLINE -9475,6775,100,-125
J 0
(0 0);
DISPLAY 0.468085 (0 0);
PAINT GREEN (0 0);
DISPLAY INVISIBLE (0 0);
FORCEPROP 2 LAST CDS_LIB pure_quanta
J 0
(0 0);
DISPLAY INVISIBLE (0 0);
FORCEPROP 2 LAST CDS_XR_PAGE_TITLE CR-228 : @T6G_MB_LIB.T6G(SCH_1):PAGE228
J 0
(-7890 5250);
DISPLAY 0.638298 (-7890 5250);
PAINT PINK (-7890 5250);
DISPLAY INVISIBLE (-7890 5250);
FORCEPROP 2 LAST CUSTOM_TXT_CDS <XR_PAGE_TITLE>
J 0
(-7890 5250);
DISPLAY 0.638298 (-7890 5250);
PAINT PINK (-7890 5250);
DISPLAY INVISIBLE (-7890 5250);
FORCEPROP 1 LAST COMMENT_BODY TRUE
J 0
(12 -13);
DISPLAY 0.978723 (12 -13);
PAINT GREEN (12 -13);
DISPLAY INVISIBLE (12 -13);
FORCEPROP 1 LAST Q_DEPT BU9
J 1
(-3763 49);
DISPLAY 1.957447 (-3763 49);
PAINT GREEN (-3763 49);
DISPLAY INVISIBLE (-3763 49);
FORCEPROP 0 LAST CDS_CON_LAST_MODIFIED Thu Aug 24 10:15:29 2023
J 0
(-1885 15);
DISPLAY INVISIBLE (-1885 15);
QUIT
